# BASEBOARD_FAB2 (Tioga Pass) — schematic netlist excerpt (pin names and nets, part order shuffled) for the footprints in the layout excerpt that follows; sources: Cadence DE-HDL packaged netlist, KiCad conversion of Wiwynn_Tioga_Pass_MB.brd

C6B18  CAP  0.22UF 16V 10% X7R  pkg 0402  page 105 : A = P3E_CPU0_PE1_PCH_TXP<9> ; B = P3E_CPU0_PE1_PCH_C_TXP<9>
R8G1  RES  22.1 1.0% CHIP  pkg 0402  page 101 : A = CLK_50M_CKMNG_BMC_2_R ; B = CLK_50M_CKMNG_BMC_2
R4D51  RES  150.0 1% CHIP  pkg 0402  page 213 : A = SVID_CLK0_CPU1_R ; B = SVID_CLK_PVCCIO_CPU1

(kicad_pcb
	(version 20260206)
	(generator "pcbnew")
	(generator_version "10.0")
	(general
		(thickness 1.6)
		(legacy_teardrops no)
	)
	(paper "A4")
	(title_block
		(title "Wiwynn_Tioga_Pass_MB.brd")
		(comment 1 "Tioga Pass / footprints 86-88 of 4770")
	)
	(layers
		(0 "F.Cu" signal "TOP")
		(4 "In1.Cu" signal "L2GND")
		(6 "In2.Cu" signal "L3")
		(8 "In3.Cu" signal "L4GND")
		(10 "In4.Cu" signal "L5")
		(12 "In5.Cu" signal "L6GND")
		(14 "In6.Cu" signal "L7VCC")
		(16 "In7.Cu" signal "L8VCC")
		(18 "In8.Cu" signal "L9GND")
		(20 "In9.Cu" signal "L10")
		(22 "In10.Cu" signal "L11GND")
		(24 "In11.Cu" signal "L12")
		(26 "In12.Cu" signal "L13GND")
		(2 "B.Cu" signal "BOTTOM")
		(9 "F.Adhes" user "F.Adhesive")
		(11 "B.Adhes" user "B.Adhesive")
		(13 "F.Paste" user "Package Geometry/Pastemask Top")
		(15 "B.Paste" user "Package Geometry/Pastemask Bottom")
		(5 "F.SilkS" user "Ref Des/Silkscreen Top")
		(7 "B.SilkS" user "Ref Des/Silkscreen Bottom")
		(1 "F.Mask" user "Board Geometry/Soldermask Top")
		(3 "B.Mask" user "Board Geometry/Soldermask Bottom")
		(17 "Dwgs.User" user "User.Drawings")
		(19 "Cmts.User" user "User.Comments")
		(21 "Eco1.User" user "User.Eco1")
		(23 "Eco2.User" user "User.Eco2")
		(25 "Edge.Cuts" user "Board Geometry/Outline")
		(27 "Margin" user)
		(31 "F.CrtYd" user "Package Geometry/Place Bound Top")
		(29 "B.CrtYd" user "Package Geometry/Place Bound Bottom")
		(35 "F.Fab" user "Ref Des/Assembly Top")
		(33 "B.Fab" user "Ref Des/Assembly Bottom")
	)
	(footprint ""
		(layer "F.Cu")
		(at 339.222588 -117.941598 90)
		(property "Reference" "C6B18"
			(at -0.8382 -0.67818 90)
			(unlocked yes)
			(layer "F.SilkS")
			(effects
				(font
					(size 0.4064 0.254)
					(thickness 0.1524)
				)
				(justify left)
			)
		)
		(property "Value" ""
			(at 0 0 90)
			(layer "F.Fab")
			(effects
				(font
					(size 1.27 1.27)
				)
			)
		)
		(duplicate_pad_numbers_are_jumpers no)
		(fp_poly
			(pts
				(xy 0.3048 -0.1016) (xy 0.3048 0.9906) (xy -0.3048 0.9906) (xy -0.3048 -0.1016)
			)
			(stroke
				(width 0)
				(type default)
			)
			(fill no)
			(layer "F.CrtYd")
		)
		(fp_line
			(start 0.3048 -0.1016)
			(end -0.3048 -0.1016)
			(stroke
				(width 0.1)
				(type default)
			)
			(layer "F.Fab")
		)
		(fp_line
			(start -0.3048 -0.1016)
			(end -0.3048 0.9906)
			(stroke
				(width 0.1)
				(type default)
			)
			(layer "F.Fab")
		)
		(fp_line
			(start 0.3048 0.9906)
			(end 0.3048 -0.1016)
			(stroke
				(width 0.1)
				(type default)
			)
			(layer "F.Fab")
		)
		(fp_line
			(start -0.3048 0.9906)
			(end 0.3048 0.9906)
			(stroke
				(width 0.1)
				(type default)
			)
			(layer "F.Fab")
		)
		(pad "1" smd rect
			(at 0 0 90)
			(size 0.508 0.508)
			(layers "F.Cu" "F.Mask" "F.Paste")
			(net "P3E_CPU0_PE1_PCH_TXP<9>")
		)
		(pad "2" smd rect
			(at 0 0.889 90)
			(size 0.508 0.508)
			(layers "F.Cu" "F.Mask" "F.Paste")
			(net "P3E_CPU0_PE1_PCH_C_TXP<9>")
		)
		(zone
			(layer "F.Cu")
			(hatch none 0.5)
			(connect_pads
				(clearance 0)
			)
			(min_thickness 0.25)
			(keepout
				(tracks allowed)
				(vias not_allowed)
				(pads allowed)
				(copperpour not_allowed)
				(footprints allowed)
			)
			(placement
				(enabled no)
				(sheetname "")
			)
			(fill
				(thermal_gap 0.5)
				(thermal_bridge_width 0.5)
				(island_removal_mode 0)
			)
			(polygon
				(pts
					(xy 339.476588 -117.687598) (xy 339.476588 -118.195598) (xy 339.857588 -118.195598) (xy 339.857588 -117.687598)
				)
			)
		)
		(zone
			(layer "F.Cu")
			(hatch none 0.5)
			(connect_pads
				(clearance 0)
			)
			(min_thickness 0.25)
			(keepout
				(tracks not_allowed)
				(vias allowed)
				(pads allowed)
				(copperpour not_allowed)
				(footprints allowed)
			)
			(placement
				(enabled no)
				(sheetname "")
			)
			(fill
				(thermal_gap 0.5)
				(thermal_bridge_width 0.5)
				(island_removal_mode 0)
			)
			(polygon
				(pts
					(xy 339.857588 -117.687598) (xy 339.857588 -118.195598) (xy 339.476588 -118.195598) (xy 339.476588 -117.687598)
				)
			)
		)
	)
	(footprint ""
		(layer "F.Cu")
		(at 164.084 -69.088 90)
		(property "Reference" "R4D51"
			(at 0 0 90)
			(layer "F.SilkS")
			(hide yes)
			(effects
				(font
					(size 1.27 1.27)
				)
			)
		)
		(property "Value" ""
			(at 0 0 90)
			(layer "F.Fab")
			(effects
				(font
					(size 1.27 1.27)
				)
			)
		)
		(duplicate_pad_numbers_are_jumpers no)
		(fp_poly
			(pts
				(xy -0.2794 -0.1016) (xy 0.2794 -0.1016) (xy 0.2794 0.9906) (xy -0.2794 0.9906)
			)
			(stroke
				(width 0)
				(type default)
			)
			(fill no)
			(layer "F.CrtYd")
		)
		(fp_line
			(start 0.2794 -0.1016)
			(end -0.2794 -0.1016)
			(stroke
				(width 0.1)
				(type default)
			)
			(layer "F.Fab")
		)
		(fp_line
			(start -0.2794 -0.1016)
			(end -0.2794 0.9906)
			(stroke
				(width 0.1)
				(type default)
			)
			(layer "F.Fab")
		)
		(fp_line
			(start 0.2794 0.9906)
			(end 0.2794 -0.1016)
			(stroke
				(width 0.1)
				(type default)
			)
			(layer "F.Fab")
		)
		(fp_line
			(start -0.2794 0.9906)
			(end 0.2794 0.9906)
			(stroke
				(width 0.1)
				(type default)
			)
			(layer "F.Fab")
		)
		(pad "1" smd rect
			(at 0 0 90)
			(size 0.508 0.508)
			(layers "F.Cu" "F.Mask" "F.Paste")
			(net "SVID_CLK0_CPU1_R")
		)
		(pad "2" smd rect
			(at 0 0.889 90)
			(size 0.508 0.508)
			(layers "F.Cu" "F.Mask" "F.Paste")
			(net "SVID_CLK_PVCCIO_CPU1")
		)
		(zone
			(layer "F.Cu")
			(hatch none 0.5)
			(connect_pads
				(clearance 0)
			)
			(min_thickness 0.25)
			(keepout
				(tracks allowed)
				(vias not_allowed)
				(pads allowed)
				(copperpour not_allowed)
				(footprints allowed)
			)
			(placement
				(enabled no)
				(sheetname "")
			)
			(fill
				(thermal_gap 0.5)
				(thermal_bridge_width 0.5)
				(island_removal_mode 0)
			)
			(polygon
				(pts
					(xy 164.338 -68.834) (xy 164.338 -69.342) (xy 164.719 -69.342) (xy 164.719 -68.834)
				)
			)
		)
		(zone
			(layer "F.Cu")
			(hatch none 0.5)
			(connect_pads
				(clearance 0)
			)
			(min_thickness 0.25)
			(keepout
				(tracks not_allowed)
				(vias allowed)
				(pads allowed)
				(copperpour not_allowed)
				(footprints allowed)
			)
			(placement
				(enabled no)
				(sheetname "")
			)
			(fill
				(thermal_gap 0.5)
				(thermal_bridge_width 0.5)
				(island_removal_mode 0)
			)
			(polygon
				(pts
					(xy 164.719 -68.834) (xy 164.719 -69.342) (xy 164.338 -69.342) (xy 164.338 -68.834)
				)
			)
		)
	)
	(footprint ""
		(layer "F.Cu")
		(at 476.377 -36.6395 180)
		(property "Reference" "R8G1"
			(at 0 0 180)
			(layer "F.SilkS")
			(hide yes)
			(effects
				(font
					(size 1.27 1.27)
				)
			)
		)
		(property "Value" ""
			(at 0 0 180)
			(layer "F.Fab")
			(effects
				(font
					(size 1.27 1.27)
				)
			)
		)
		(duplicate_pad_numbers_are_jumpers no)
		(fp_poly
			(pts
				(xy -0.2794 -0.1016) (xy 0.2794 -0.1016) (xy 0.2794 0.9906) (xy -0.2794 0.9906)
			)
			(stroke
				(width 0)
				(type default)
			)
			(fill no)
			(layer "F.CrtYd")
		)
		(fp_line
			(start 0.2794 0.9906)
			(end 0.2794 -0.1016)
			(stroke
				(width 0.1)
				(type default)
			)
			(layer "F.Fab")
		)
		(fp_line
			(start 0.2794 -0.1016)
			(end -0.2794 -0.1016)
			(stroke
				(width 0.1)
				(type default)
			)
			(layer "F.Fab")
		)
		(fp_line
			(start -0.2794 0.9906)
			(end 0.2794 0.9906)
			(stroke
				(width 0.1)
				(type default)
			)
			(layer "F.Fab")
		)
		(fp_line
			(start -0.2794 -0.1016)
			(end -0.2794 0.9906)
			(stroke
				(width 0.1)
				(type default)
			)
			(layer "F.Fab")
		)
		(pad "1" smd rect
			(at 0 0 180)
			(size 0.508 0.508)
			(layers "F.Cu" "F.Mask" "F.Paste")
			(net "CLK_50M_CKMNG_BMC_2_R")
		)
		(pad "2" smd rect
			(at 0 0.889 180)
			(size 0.508 0.508)
			(layers "F.Cu" "F.Mask" "F.Paste")
			(net "CLK_50M_CKMNG_BMC_2")
		)
		(zone
			(layer "F.Cu")
			(hatch none 0.5)
			(connect_pads
				(clearance 0)
			)
			(min_thickness 0.25)
			(keepout
				(tracks not_allowed)
				(vias allowed)
				(pads allowed)
				(copperpour not_allowed)
				(footprints allowed)
			)
			(placement
				(enabled no)
				(sheetname "")
			)
			(fill
				(thermal_gap 0.5)
				(thermal_bridge_width 0.5)
				(island_removal_mode 0)
			)
			(polygon
				(pts
					(xy 476.631 -37.2745) (xy 476.123 -37.2745) (xy 476.123 -36.8935) (xy 476.631 -36.8935)
				)
			)
		)
		(zone
			(layer "F.Cu")
			(hatch none 0.5)
			(connect_pads
				(clearance 0)
			)
			(min_thickness 0.25)
			(keepout
				(tracks allowed)
				(vias not_allowed)
				(pads allowed)
				(copperpour not_allowed)
				(footprints allowed)
			)
			(placement
				(enabled no)
				(sheetname "")
			)
			(fill
				(thermal_gap 0.5)
				(thermal_bridge_width 0.5)
				(island_removal_mode 0)
			)
			(polygon
				(pts
					(xy 476.631 -36.8935) (xy 476.123 -36.8935) (xy 476.123 -37.2745) (xy 476.631 -37.2745)
				)
			)
		)
	)
)
